# S9S_MB_2U (Grand Teton) — schematic netlist excerpt (pin names and nets, part order shuffled) for the footprints in the layout excerpt that follows; sources: Cadence DE-HDL packaged netlist, KiCad conversion of 03242023_DA0F0TMBIJ0_F0T_Motherboard_J_brd_V01_OCP.brd

C1996  Q_CAP_DIFFBUS  DIFF BUS_0.22UF 6.3V 20% X6S  pkg C0201  page 181 : \1\ = P3E_PCH_E1S_TX_DN<0> ; \2\ = P3E_PCH_E1S_TX_C_DN<0>
PC214  Q_CAP  0.1UF 25V 10% EMPTY  pkg 0402  page 274 : A = PVCCINFAON_CPU0_CSPIN ; B = GND

(kicad_pcb
	(version 20260206)
	(generator "pcbnew")
	(generator_version "10.0")
	(general
		(thickness 1.6)
		(legacy_teardrops no)
	)
	(paper "A4")
	(title_block
		(title "03242023_DA0F0TMBIJ0_F0T_Motherboard_J_brd_V01_OCP.brd")
		(comment 1 "Grand Teton / footprints 1256-1257 of 6105")
	)
	(layers
		(0 "F.Cu" signal "TOP")
		(4 "In1.Cu" signal "GND")
		(6 "In2.Cu" signal "IN1")
		(8 "In3.Cu" signal "GND1")
		(10 "In4.Cu" signal "IN2")
		(12 "In5.Cu" signal "GND2")
		(14 "In6.Cu" signal "IN3")
		(16 "In7.Cu" signal "GND3")
		(18 "In8.Cu" signal "VCC")
		(20 "In9.Cu" signal "VCC1")
		(22 "In10.Cu" signal "GND4")
		(24 "In11.Cu" signal "IN4")
		(26 "In12.Cu" signal "GND5")
		(28 "In13.Cu" signal "IN5")
		(30 "In14.Cu" signal "GND6")
		(32 "In15.Cu" signal "IN6")
		(34 "In16.Cu" signal "GND7")
		(2 "B.Cu" signal "BOTTOM")
		(9 "F.Adhes" user "F.Adhesive")
		(11 "B.Adhes" user "B.Adhesive")
		(13 "F.Paste" user "Package Geometry/Pastemask Top")
		(15 "B.Paste" user "Package Geometry/Pastemask Bottom")
		(5 "F.SilkS" user "Ref Des/Silkscreen Top")
		(7 "B.SilkS" user "Ref Des/Silkscreen Bottom")
		(1 "F.Mask" user "Board Geometry/Soldermask Top")
		(3 "B.Mask" user "Board Geometry/Soldermask Bottom")
		(17 "Dwgs.User" user "User.Drawings")
		(19 "Cmts.User" user "User.Comments")
		(21 "Eco1.User" user "User.Eco1")
		(23 "Eco2.User" user "User.Eco2")
		(25 "Edge.Cuts" user "Board Geometry/Outline")
		(27 "Margin" user)
		(31 "F.CrtYd" user "Package Geometry/Place Bound Top")
		(29 "B.CrtYd" user "Package Geometry/Place Bound Bottom")
		(35 "F.Fab" user "Ref Des/Assembly Top")
		(33 "B.Fab" user "Ref Des/Assembly Bottom")
	)
	(footprint ""
		(layer "F.Cu")
		(at 420.682166 -136.162034 180)
		(property "Reference" "PC214"
			(at 0 0 180)
			(layer "F.SilkS")
			(hide yes)
			(effects
				(font
					(size 1.27 1.27)
				)
			)
		)
		(property "Value" ""
			(at 0 0 180)
			(layer "F.Fab")
			(effects
				(font
					(size 1.27 1.27)
				)
			)
		)
		(duplicate_pad_numbers_are_jumpers no)
		(fp_line
			(start 0.7874 0.4064)
			(end -0.7874 0.4064)
			(stroke
				(width 0.1524)
				(type default)
			)
			(layer "F.SilkS")
		)
		(fp_line
			(start 0.7874 -0.4064)
			(end 0.7874 0.4064)
			(stroke
				(width 0.1524)
				(type default)
			)
			(layer "F.SilkS")
		)
		(fp_line
			(start -0.7874 0.4064)
			(end -0.7874 -0.4064)
			(stroke
				(width 0.1524)
				(type default)
			)
			(layer "F.SilkS")
		)
		(fp_line
			(start -0.7874 -0.4064)
			(end 0.7874 -0.4064)
			(stroke
				(width 0.1524)
				(type default)
			)
			(layer "F.SilkS")
		)
		(fp_line
			(start 0.67945 0.3048)
			(end 0.120396 0.3048)
			(stroke
				(width 0.1)
				(type default)
			)
			(layer "F.Fab")
		)
		(fp_line
			(start 0.67945 -0.3048)
			(end 0.67945 0.3048)
			(stroke
				(width 0.1)
				(type default)
			)
			(layer "F.Fab")
		)
		(fp_line
			(start 0.12065 -0.2794)
			(end 0.12065 -0.3048)
			(stroke
				(width 0.1)
				(type default)
			)
			(layer "F.Fab")
		)
		(fp_line
			(start 0.12065 -0.3048)
			(end 0.67945 -0.3048)
			(stroke
				(width 0.1)
				(type default)
			)
			(layer "F.Fab")
		)
		(fp_line
			(start 0.120396 0.3048)
			(end 0.120396 0.2794)
			(stroke
				(width 0.1)
				(type default)
			)
			(layer "F.Fab")
		)
		(fp_line
			(start 0.120396 0.2794)
			(end -0.12065 0.2794)
			(stroke
				(width 0.1)
				(type default)
			)
			(layer "F.Fab")
		)
		(fp_line
			(start -0.12065 0.3048)
			(end -0.67945 0.3048)
			(stroke
				(width 0.1)
				(type default)
			)
			(layer "F.Fab")
		)
		(fp_line
			(start -0.12065 0.2794)
			(end -0.12065 0.3048)
			(stroke
				(width 0.1)
				(type default)
			)
			(layer "F.Fab")
		)
		(fp_line
			(start -0.12065 -0.2794)
			(end 0.12065 -0.2794)
			(stroke
				(width 0.1)
				(type default)
			)
			(layer "F.Fab")
		)
		(fp_line
			(start -0.12065 -0.305054)
			(end -0.12065 -0.2794)
			(stroke
				(width 0.1)
				(type default)
			)
			(layer "F.Fab")
		)
		(fp_line
			(start -0.67945 0.3048)
			(end -0.67945 -0.305054)
			(stroke
				(width 0.1)
				(type default)
			)
			(layer "F.Fab")
		)
		(fp_line
			(start -0.67945 -0.305054)
			(end -0.12065 -0.305054)
			(stroke
				(width 0.1)
				(type default)
			)
			(layer "F.Fab")
		)
		(pad "1" smd circle
			(at -0.40005 0 180)
			(size 0 0)
			(layers "F.Cu" "F.Mask" "F.Paste")
			(net "PVCCINFAON_CPU0_CSPIN")
		)
		(pad "2" smd circle
			(at 0.40005 0 180)
			(size 0 0)
			(layers "F.Cu" "F.Mask" "F.Paste")
			(net "GND")
		)
	)
	(footprint ""
		(layer "F.Cu")
		(at 239.152684 -52.92725 180)
		(property "Reference" "C1996"
			(at 0 0 180)
			(layer "F.SilkS")
			(hide yes)
			(effects
				(font
					(size 1.27 1.27)
				)
			)
		)
		(property "Value" ""
			(at 0 0 180)
			(layer "F.Fab")
			(effects
				(font
					(size 1.27 1.27)
				)
			)
		)
		(duplicate_pad_numbers_are_jumpers no)
		(fp_line
			(start 0.299974 0.150114)
			(end -0.299974 0.150114)
			(stroke
				(width 0.1)
				(type default)
			)
			(layer "F.Fab")
		)
		(fp_line
			(start 0.299974 -0.150114)
			(end 0.299974 0.150114)
			(stroke
				(width 0.1)
				(type default)
			)
			(layer "F.Fab")
		)
		(fp_line
			(start -0.299974 0.150114)
			(end -0.299974 -0.150114)
			(stroke
				(width 0.1)
				(type default)
			)
			(layer "F.Fab")
		)
		(fp_line
			(start -0.299974 -0.150114)
			(end 0.299974 -0.150114)
			(stroke
				(width 0.1)
				(type default)
			)
			(layer "F.Fab")
		)
		(pad "1" smd rect
			(at -0.2667 0 180)
			(size 0.3048 0.381)
			(layers "F.Cu" "F.Mask" "F.Paste")
			(net "P3E_PCH_E1S_TX_DN<0>")
		)
		(pad "2" smd rect
			(at 0.2667 0 180)
			(size 0.3048 0.381)
			(layers "F.Cu" "F.Mask" "F.Paste")
			(net "P3E_PCH_E1S_TX_C_DN<0>")
		)
		(zone
			(layer "In1.Cu")
			(hatch none 0.5)
			(connect_pads
				(clearance 0)
			)
			(min_thickness 0.25)
			(keepout
				(tracks not_allowed)
				(vias allowed)
				(pads allowed)
				(copperpour not_allowed)
				(footprints allowed)
			)
			(placement
				(enabled no)
				(sheetname "")
			)
			(fill
				(thermal_gap 0.5)
				(thermal_bridge_width 0.5)
				(island_removal_mode 0)
			)
			(polygon
				(pts
					(arc
						(start 239.012984 -53.167534)
						(mid 239.066866 -53.145216)
						(end 239.089184 -53.091334)
					)
					(arc
						(start 239.089184 -52.761134)
						(mid 239.066866 -52.707252)
						(end 239.012984 -52.684934)
					)
					(arc
						(start 238.758984 -52.684934)
						(mid 238.705102 -52.707252)
						(end 238.682784 -52.761134)
					)
					(arc
						(start 238.682784 -53.091334)
						(mid 238.705102 -53.145216)
						(end 238.758984 -53.167534)
					)
				)
			)
		)
		(zone
			(layer "In1.Cu")
			(hatch none 0.5)
			(connect_pads
				(clearance 0)
			)
			(min_thickness 0.25)
			(keepout
				(tracks not_allowed)
				(vias allowed)
				(pads allowed)
				(copperpour not_allowed)
				(footprints allowed)
			)
			(placement
				(enabled no)
				(sheetname "")
			)
			(fill
				(thermal_gap 0.5)
				(thermal_bridge_width 0.5)
				(island_removal_mode 0)
			)
			(polygon
				(pts
					(arc
						(start 239.546384 -53.167534)
						(mid 239.600266 -53.145216)
						(end 239.622584 -53.091334)
					)
					(arc
						(start 239.622584 -52.761134)
						(mid 239.600266 -52.707252)
						(end 239.546384 -52.684934)
					)
					(arc
						(start 239.292384 -52.684934)
						(mid 239.238502 -52.707252)
						(end 239.216184 -52.761134)
					)
					(arc
						(start 239.216184 -53.091334)
						(mid 239.238502 -53.145216)
						(end 239.292384 -53.167534)
					)
				)
			)
		)
	)
)
